(kicad_pcb
	(version 20260206)
	(generator "pcbnew")
	(generator_version "10.0")
	(general
		(thickness 1.6)
		(legacy_teardrops no)
	)
	(paper "A4")
	(title_block
		(title "01162023_DA0F0TEBIF0_F0T_Expander_BD_F_brd_V02_OCP.brd")
		(comment 1 "Grand Teton / footprints 8017-8024 of 9728")
	)
	(layers
		(0 "F.Cu" signal "TOP")
		(4 "In1.Cu" signal "GND")
		(6 "In2.Cu" signal "VCC")
		(8 "In3.Cu" signal "VCC1")
		(10 "In4.Cu" signal "GND1")
		(12 "In5.Cu" signal "IN1")
		(14 "In6.Cu" signal "GND2")
		(16 "In7.Cu" signal "IN2")
		(18 "In8.Cu" signal "GND3")
		(20 "In9.Cu" signal "IN3")
		(22 "In10.Cu" signal "GND4")
		(24 "In11.Cu" signal "IN4")
		(26 "In12.Cu" signal "GND5")
		(28 "In13.Cu" signal "IN5")
		(30 "In14.Cu" signal "GND6")
		(32 "In15.Cu" signal "IN6")
		(34 "In16.Cu" signal "GND7")
		(2 "B.Cu" signal "BOTTOM")
		(9 "F.Adhes" user "F.Adhesive")
		(11 "B.Adhes" user "B.Adhesive")
		(13 "F.Paste" user "Package Geometry/Pastemask Top")
		(15 "B.Paste" user "Package Geometry/Pastemask Bottom")
		(5 "F.SilkS" user "Ref Des/Silkscreen Top")
		(7 "B.SilkS" user "Ref Des/Silkscreen Bottom")
		(1 "F.Mask" user "Board Geometry/Soldermask Top")
		(3 "B.Mask" user "Board Geometry/Soldermask Bottom")
		(17 "Dwgs.User" user "User.Drawings")
		(19 "Cmts.User" user "User.Comments")
		(21 "Eco1.User" user "User.Eco1")
		(23 "Eco2.User" user "User.Eco2")
		(25 "Edge.Cuts" user "Board Geometry/Outline")
		(27 "Margin" user)
		(31 "F.CrtYd" user "Package Geometry/Place Bound Top")
		(29 "B.CrtYd" user "Package Geometry/Place Bound Bottom")
		(35 "F.Fab" user "Ref Des/Assembly Top")
		(33 "B.Fab" user "Ref Des/Assembly Bottom")
	)
	(footprint ""
		(layer "B.Cu")
		(at 293.74973 -292.099746 90)
		(property "Reference" "C1742"
			(at 0 0 90)
			(layer "B.SilkS")
			(hide yes)
			(effects
				(font
					(size 1.27 1.27)
				)
				(justify mirror)
			)
		)
		(property "Value" ""
			(at 0 0 90)
			(layer "B.Fab")
			(effects
				(font
					(size 1.27 1.27)
				)
				(justify mirror)
			)
		)
		(duplicate_pad_numbers_are_jumpers no)
		(fp_line
			(start 0.299974 -0.150114)
			(end -0.299974 -0.150114)
			(stroke
				(width 0.1)
				(type default)
			)
			(layer "B.Fab")
		)
		(fp_line
			(start -0.299974 -0.150114)
			(end -0.299974 0.150114)
			(stroke
				(width 0.1)
				(type default)
			)
			(layer "B.Fab")
		)
		(fp_line
			(start 0.299974 0.150114)
			(end 0.299974 -0.150114)
			(stroke
				(width 0.1)
				(type default)
			)
			(layer "B.Fab")
		)
		(fp_line
			(start -0.299974 0.150114)
			(end 0.299974 0.150114)
			(stroke
				(width 0.1)
				(type default)
			)
			(layer "B.Fab")
		)
		(pad "1" smd rect
			(at 0.2667 0 270)
			(size 0.3048 0.381)
			(layers "B.Cu" "B.Mask" "B.Paste")
			(net "P0V8_SERDES_VDDA_PEX2")
		)
		(pad "2" smd rect
			(at -0.2667 0 270)
			(size 0.3048 0.381)
			(layers "B.Cu" "B.Mask" "B.Paste")
			(net "GND")
		)
	)
	(footprint ""
		(layer "B.Cu")
		(at 424.02379 -289.724846 90)
		(property "Reference" "R969"
			(at 0 0 90)
			(layer "B.SilkS")
			(hide yes)
			(effects
				(font
					(size 1.27 1.27)
				)
				(justify mirror)
			)
		)
		(property "Value" ""
			(at 0 0 90)
			(layer "B.Fab")
			(effects
				(font
					(size 1.27 1.27)
				)
				(justify mirror)
			)
		)
		(duplicate_pad_numbers_are_jumpers no)
		(fp_line
			(start 0.7874 -0.4064)
			(end -0.7874 -0.4064)
			(stroke
				(width 0.1524)
				(type default)
			)
			(layer "B.SilkS")
		)
		(fp_line
			(start -0.7874 -0.4064)
			(end -0.7874 0.4064)
			(stroke
				(width 0.1524)
				(type default)
			)
			(layer "B.SilkS")
		)
		(fp_line
			(start 0.7874 0.4064)
			(end 0.7874 -0.4064)
			(stroke
				(width 0.1524)
				(type default)
			)
			(layer "B.SilkS")
		)
		(fp_line
			(start -0.7874 0.4064)
			(end 0.7874 0.4064)
			(stroke
				(width 0.1524)
				(type default)
			)
			(layer "B.SilkS")
		)
		(fp_line
			(start 0.67945 -0.305054)
			(end 0.12065 -0.305054)
			(stroke
				(width 0.1)
				(type default)
			)
			(layer "B.Fab")
		)
		(fp_line
			(start 0.12065 -0.305054)
			(end 0.12065 -0.2794)
			(stroke
				(width 0.1)
				(type default)
			)
			(layer "B.Fab")
		)
		(fp_line
			(start -0.12065 -0.3048)
			(end -0.67945 -0.3048)
			(stroke
				(width 0.1)
				(type default)
			)
			(layer "B.Fab")
		)
		(fp_line
			(start -0.67945 -0.3048)
			(end -0.67945 0.3048)
			(stroke
				(width 0.1)
				(type default)
			)
			(layer "B.Fab")
		)
		(fp_line
			(start 0.12065 -0.2794)
			(end -0.12065 -0.2794)
			(stroke
				(width 0.1)
				(type default)
			)
			(layer "B.Fab")
		)
		(fp_line
			(start -0.12065 -0.2794)
			(end -0.12065 -0.3048)
			(stroke
				(width 0.1)
				(type default)
			)
			(layer "B.Fab")
		)
		(fp_line
			(start 0.12065 0.2794)
			(end 0.12065 0.3048)
			(stroke
				(width 0.1)
				(type default)
			)
			(layer "B.Fab")
		)
		(fp_line
			(start -0.120396 0.2794)
			(end 0.12065 0.2794)
			(stroke
				(width 0.1)
				(type default)
			)
			(layer "B.Fab")
		)
		(fp_line
			(start 0.67945 0.3048)
			(end 0.67945 -0.305054)
			(stroke
				(width 0.1)
				(type default)
			)
			(layer "B.Fab")
		)
		(fp_line
			(start 0.12065 0.3048)
			(end 0.67945 0.3048)
			(stroke
				(width 0.1)
				(type default)
			)
			(layer "B.Fab")
		)
		(fp_line
			(start -0.120396 0.3048)
			(end -0.120396 0.2794)
			(stroke
				(width 0.1)
				(type default)
			)
			(layer "B.Fab")
		)
		(fp_line
			(start -0.67945 0.3048)
			(end -0.120396 0.3048)
			(stroke
				(width 0.1)
				(type default)
			)
			(layer "B.Fab")
		)
		(pad "1" smd circle
			(at 0.40005 0 270)
			(size 0 0)
			(layers "B.Cu" "B.Mask" "B.Paste")
			(net "UART_PEX3_SDB_TX")
		)
		(pad "2" smd circle
			(at -0.40005 0 270)
			(size 0 0)
			(layers "B.Cu" "B.Mask" "B.Paste")
			(net "UART_PEX3_SDB_R_TX")
		)
	)
	(footprint ""
		(layer "B.Cu")
		(at 248.940574 -91.918028 90)
		(property "Reference" "R1077"
			(at 0 0 90)
			(layer "B.SilkS")
			(hide yes)
			(effects
				(font
					(size 1.27 1.27)
				)
				(justify mirror)
			)
		)
		(property "Value" ""
			(at 0 0 90)
			(layer "B.Fab")
			(effects
				(font
					(size 1.27 1.27)
				)
				(justify mirror)
			)
		)
		(duplicate_pad_numbers_are_jumpers no)
		(fp_line
			(start 0.7874 -0.4064)
			(end -0.7874 -0.4064)
			(stroke
				(width 0.1524)
				(type default)
			)
			(layer "B.SilkS")
		)
		(fp_line
			(start -0.7874 -0.4064)
			(end -0.7874 0.4064)
			(stroke
				(width 0.1524)
				(type default)
			)
			(layer "B.SilkS")
		)
		(fp_line
			(start 0.7874 0.4064)
			(end 0.7874 -0.4064)
			(stroke
				(width 0.1524)
				(type default)
			)
			(layer "B.SilkS")
		)
		(fp_line
			(start -0.7874 0.4064)
			(end 0.7874 0.4064)
			(stroke
				(width 0.1524)
				(type default)
			)
			(layer "B.SilkS")
		)
		(fp_line
			(start 0.67945 -0.305054)
			(end 0.12065 -0.305054)
			(stroke
				(width 0.1)
				(type default)
			)
			(layer "B.Fab")
		)
		(fp_line
			(start 0.12065 -0.305054)
			(end 0.12065 -0.2794)
			(stroke
				(width 0.1)
				(type default)
			)
			(layer "B.Fab")
		)
		(fp_line
			(start -0.12065 -0.3048)
			(end -0.67945 -0.3048)
			(stroke
				(width 0.1)
				(type default)
			)
			(layer "B.Fab")
		)
		(fp_line
			(start -0.67945 -0.3048)
			(end -0.67945 0.3048)
			(stroke
				(width 0.1)
				(type default)
			)
			(layer "B.Fab")
		)
		(fp_line
			(start 0.12065 -0.2794)
			(end -0.12065 -0.2794)
			(stroke
				(width 0.1)
				(type default)
			)
			(layer "B.Fab")
		)
		(fp_line
			(start -0.12065 -0.2794)
			(end -0.12065 -0.3048)
			(stroke
				(width 0.1)
				(type default)
			)
			(layer "B.Fab")
		)
		(fp_line
			(start 0.12065 0.2794)
			(end 0.12065 0.3048)
			(stroke
				(width 0.1)
				(type default)
			)
			(layer "B.Fab")
		)
		(fp_line
			(start -0.120396 0.2794)
			(end 0.12065 0.2794)
			(stroke
				(width 0.1)
				(type default)
			)
			(layer "B.Fab")
		)
		(fp_line
			(start 0.67945 0.3048)
			(end 0.67945 -0.305054)
			(stroke
				(width 0.1)
				(type default)
			)
			(layer "B.Fab")
		)
		(fp_line
			(start 0.12065 0.3048)
			(end 0.67945 0.3048)
			(stroke
				(width 0.1)
				(type default)
			)
			(layer "B.Fab")
		)
		(fp_line
			(start -0.120396 0.3048)
			(end -0.120396 0.2794)
			(stroke
				(width 0.1)
				(type default)
			)
			(layer "B.Fab")
		)
		(fp_line
			(start -0.67945 0.3048)
			(end -0.120396 0.3048)
			(stroke
				(width 0.1)
				(type default)
			)
			(layer "B.Fab")
		)
		(pad "1" smd circle
			(at 0.40005 0 270)
			(size 0 0)
			(layers "B.Cu" "B.Mask" "B.Paste")
			(net "P3V3")
		)
		(pad "2" smd circle
			(at -0.40005 0 270)
			(size 0 0)
			(layers "B.Cu" "B.Mask" "B.Paste")
			(net "PU_CLK_PFT_LOST_N")
		)
	)
	(footprint ""
		(layer "B.Cu")
		(at 347.428312 -323.15531 -90)
		(property "Reference" "R6513"
			(at 0 0 90)
			(layer "B.SilkS")
			(hide yes)
			(effects
				(font
					(size 1.27 1.27)
				)
				(justify mirror)
			)
		)
		(property "Value" ""
			(at 0 0 90)
			(layer "B.Fab")
			(effects
				(font
					(size 1.27 1.27)
				)
				(justify mirror)
			)
		)
		(duplicate_pad_numbers_are_jumpers no)
		(fp_line
			(start -0.7874 0.4064)
			(end 0.7874 0.4064)
			(stroke
				(width 0.1524)
				(type default)
			)
			(layer "B.SilkS")
		)
		(fp_line
			(start 0.7874 0.4064)
			(end 0.7874 -0.4064)
			(stroke
				(width 0.1524)
				(type default)
			)
			(layer "B.SilkS")
		)
		(fp_line
			(start -0.7874 -0.4064)
			(end -0.7874 0.4064)
			(stroke
				(width 0.1524)
				(type default)
			)
			(layer "B.SilkS")
		)
		(fp_line
			(start 0.7874 -0.4064)
			(end -0.7874 -0.4064)
			(stroke
				(width 0.1524)
				(type default)
			)
			(layer "B.SilkS")
		)
		(fp_line
			(start -0.67945 0.3048)
			(end -0.120396 0.3048)
			(stroke
				(width 0.1)
				(type default)
			)
			(layer "B.Fab")
		)
		(fp_line
			(start -0.120396 0.3048)
			(end -0.120396 0.2794)
			(stroke
				(width 0.1)
				(type default)
			)
			(layer "B.Fab")
		)
		(fp_line
			(start 0.12065 0.3048)
			(end 0.67945 0.3048)
			(stroke
				(width 0.1)
				(type default)
			)
			(layer "B.Fab")
		)
		(fp_line
			(start 0.67945 0.3048)
			(end 0.67945 -0.305054)
			(stroke
				(width 0.1)
				(type default)
			)
			(layer "B.Fab")
		)
		(fp_line
			(start -0.120396 0.2794)
			(end 0.12065 0.2794)
			(stroke
				(width 0.1)
				(type default)
			)
			(layer "B.Fab")
		)
		(fp_line
			(start 0.12065 0.2794)
			(end 0.12065 0.3048)
			(stroke
				(width 0.1)
				(type default)
			)
			(layer "B.Fab")
		)
		(fp_line
			(start -0.12065 -0.2794)
			(end -0.12065 -0.3048)
			(stroke
				(width 0.1)
				(type default)
			)
			(layer "B.Fab")
		)
		(fp_line
			(start 0.12065 -0.2794)
			(end -0.12065 -0.2794)
			(stroke
				(width 0.1)
				(type default)
			)
			(layer "B.Fab")
		)
		(fp_line
			(start -0.67945 -0.3048)
			(end -0.67945 0.3048)
			(stroke
				(width 0.1)
				(type default)
			)
			(layer "B.Fab")
		)
		(fp_line
			(start -0.12065 -0.3048)
			(end -0.67945 -0.3048)
			(stroke
				(width 0.1)
				(type default)
			)
			(layer "B.Fab")
		)
		(fp_line
			(start 0.12065 -0.305054)
			(end 0.12065 -0.2794)
			(stroke
				(width 0.1)
				(type default)
			)
			(layer "B.Fab")
		)
		(fp_line
			(start 0.67945 -0.305054)
			(end 0.12065 -0.305054)
			(stroke
				(width 0.1)
				(type default)
			)
			(layer "B.Fab")
		)
		(pad "1" smd circle
			(at 0.40005 0 90)
			(size 0 0)
			(layers "B.Cu" "B.Mask" "B.Paste")
			(net "P0V8_SERDES_VDDA_PEX2")
		)
		(pad "2" smd circle
			(at -0.40005 0 90)
			(size 0 0)
			(layers "B.Cu" "B.Mask" "B.Paste")
			(net "P0V8_SERDES_VDDA_PEX2_C6")
		)
	)
	(footprint ""
		(layer "B.Cu")
		(at 210.749896 -218.308936 180)
		(property "Reference" "C2145"
			(at 0 0 0)
			(layer "B.SilkS")
			(hide yes)
			(effects
				(font
					(size 1.27 1.27)
				)
				(justify mirror)
			)
		)
		(property "Value" ""
			(at 0 0 0)
			(layer "B.Fab")
			(effects
				(font
					(size 1.27 1.27)
				)
				(justify mirror)
			)
		)
		(duplicate_pad_numbers_are_jumpers no)
		(fp_line
			(start 0.7874 0.4064)
			(end 0.7874 -0.4064)
			(stroke
				(width 0.1524)
				(type default)
			)
			(layer "B.SilkS")
		)
		(fp_line
			(start 0.7874 -0.4064)
			(end -0.7874 -0.4064)
			(stroke
				(width 0.1524)
				(type default)
			)
			(layer "B.SilkS")
		)
		(fp_line
			(start -0.7874 0.4064)
			(end 0.7874 0.4064)
			(stroke
				(width 0.1524)
				(type default)
			)
			(layer "B.SilkS")
		)
		(fp_line
			(start -0.7874 -0.4064)
			(end -0.7874 0.4064)
			(stroke
				(width 0.1524)
				(type default)
			)
			(layer "B.SilkS")
		)
		(fp_line
			(start 0.67945 0.3048)
			(end 0.67945 -0.305054)
			(stroke
				(width 0.1)
				(type default)
			)
			(layer "B.Fab")
		)
		(fp_line
			(start 0.67945 -0.305054)
			(end 0.12065 -0.305054)
			(stroke
				(width 0.1)
				(type default)
			)
			(layer "B.Fab")
		)
		(fp_line
			(start 0.12065 0.3048)
			(end 0.67945 0.3048)
			(stroke
				(width 0.1)
				(type default)
			)
			(layer "B.Fab")
		)
		(fp_line
			(start 0.12065 0.2794)
			(end 0.12065 0.3048)
			(stroke
				(width 0.1)
				(type default)
			)
			(layer "B.Fab")
		)
		(fp_line
			(start 0.12065 -0.2794)
			(end -0.12065 -0.2794)
			(stroke
				(width 0.1)
				(type default)
			)
			(layer "B.Fab")
		)
		(fp_line
			(start 0.12065 -0.305054)
			(end 0.12065 -0.2794)
			(stroke
				(width 0.1)
				(type default)
			)
			(layer "B.Fab")
		)
		(fp_line
			(start -0.120396 0.3048)
			(end -0.120396 0.2794)
			(stroke
				(width 0.1)
				(type default)
			)
			(layer "B.Fab")
		)
		(fp_line
			(start -0.120396 0.2794)
			(end 0.12065 0.2794)
			(stroke
				(width 0.1)
				(type default)
			)
			(layer "B.Fab")
		)
		(fp_line
			(start -0.12065 -0.2794)
			(end -0.12065 -0.3048)
			(stroke
				(width 0.1)
				(type default)
			)
			(layer "B.Fab")
		)
		(fp_line
			(start -0.12065 -0.3048)
			(end -0.67945 -0.3048)
			(stroke
				(width 0.1)
				(type default)
			)
			(layer "B.Fab")
		)
		(fp_line
			(start -0.67945 0.3048)
			(end -0.120396 0.3048)
			(stroke
				(width 0.1)
				(type default)
			)
			(layer "B.Fab")
		)
		(fp_line
			(start -0.67945 -0.3048)
			(end -0.67945 0.3048)
			(stroke
				(width 0.1)
				(type default)
			)
			(layer "B.Fab")
		)
		(pad "1" smd circle
			(at 0.40005 0)
			(size 0 0)
			(layers "B.Cu" "B.Mask" "B.Paste")
			(net "GND")
		)
		(pad "2" smd circle
			(at -0.40005 0)
			(size 0 0)
			(layers "B.Cu" "B.Mask" "B.Paste")
			(net "USB_DEBUG_RST_BTN_R_N")
		)
	)
	(footprint ""
		(layer "B.Cu")
		(at 116.224558 -282.166822 90)
		(property "Reference" "R6763"
			(at 0 0 90)
			(layer "B.SilkS")
			(hide yes)
			(effects
				(font
					(size 1.27 1.27)
				)
				(justify mirror)
			)
		)
		(property "Value" ""
			(at 0 0 90)
			(layer "B.Fab")
			(effects
				(font
					(size 1.27 1.27)
				)
				(justify mirror)
			)
		)
		(duplicate_pad_numbers_are_jumpers no)
		(fp_line
			(start 0.7874 -0.4064)
			(end -0.7874 -0.4064)
			(stroke
				(width 0.1524)
				(type default)
			)
			(layer "B.SilkS")
		)
		(fp_line
			(start -0.7874 -0.4064)
			(end -0.7874 0.4064)
			(stroke
				(width 0.1524)
				(type default)
			)
			(layer "B.SilkS")
		)
		(fp_line
			(start 0.7874 0.4064)
			(end 0.7874 -0.4064)
			(stroke
				(width 0.1524)
				(type default)
			)
			(layer "B.SilkS")
		)
		(fp_line
			(start -0.7874 0.4064)
			(end 0.7874 0.4064)
			(stroke
				(width 0.1524)
				(type default)
			)
			(layer "B.SilkS")
		)
		(fp_line
			(start 0.67945 -0.305054)
			(end 0.12065 -0.305054)
			(stroke
				(width 0.1)
				(type default)
			)
			(layer "B.Fab")
		)
		(fp_line
			(start 0.12065 -0.305054)
			(end 0.12065 -0.2794)
			(stroke
				(width 0.1)
				(type default)
			)
			(layer "B.Fab")
		)
		(fp_line
			(start -0.12065 -0.3048)
			(end -0.67945 -0.3048)
			(stroke
				(width 0.1)
				(type default)
			)
			(layer "B.Fab")
		)
		(fp_line
			(start -0.67945 -0.3048)
			(end -0.67945 0.3048)
			(stroke
				(width 0.1)
				(type default)
			)
			(layer "B.Fab")
		)
		(fp_line
			(start 0.12065 -0.2794)
			(end -0.12065 -0.2794)
			(stroke
				(width 0.1)
				(type default)
			)
			(layer "B.Fab")
		)
		(fp_line
			(start -0.12065 -0.2794)
			(end -0.12065 -0.3048)
			(stroke
				(width 0.1)
				(type default)
			)
			(layer "B.Fab")
		)
		(fp_line
			(start 0.12065 0.2794)
			(end 0.12065 0.3048)
			(stroke
				(width 0.1)
				(type default)
			)
			(layer "B.Fab")
		)
		(fp_line
			(start -0.120396 0.2794)
			(end 0.12065 0.2794)
			(stroke
				(width 0.1)
				(type default)
			)
			(layer "B.Fab")
		)
		(fp_line
			(start 0.67945 0.3048)
			(end 0.67945 -0.305054)
			(stroke
				(width 0.1)
				(type default)
			)
			(layer "B.Fab")
		)
		(fp_line
			(start 0.12065 0.3048)
			(end 0.67945 0.3048)
			(stroke
				(width 0.1)
				(type default)
			)
			(layer "B.Fab")
		)
		(fp_line
			(start -0.120396 0.3048)
			(end -0.120396 0.2794)
			(stroke
				(width 0.1)
				(type default)
			)
			(layer "B.Fab")
		)
		(fp_line
			(start -0.67945 0.3048)
			(end -0.120396 0.3048)
			(stroke
				(width 0.1)
				(type default)
			)
			(layer "B.Fab")
		)
		(pad "1" smd circle
			(at 0.40005 0 270)
			(size 0 0)
			(layers "B.Cu" "B.Mask" "B.Paste")
			(net "P0V8_PEX0_VCC2")
		)
		(pad "2" smd circle
			(at -0.40005 0 270)
			(size 0 0)
			(layers "B.Cu" "B.Mask" "B.Paste")
			(net "P0V8_PEX0_EN2")
		)
	)
	(footprint ""
		(layer "B.Cu")
		(at 62.051184 -305.399948 -90)
		(property "Reference" "C2964"
			(at 0 0 90)
			(layer "B.SilkS")
			(hide yes)
			(effects
				(font
					(size 1.27 1.27)
				)
				(justify mirror)
			)
		)
		(property "Value" ""
			(at 0 0 90)
			(layer "B.Fab")
			(effects
				(font
					(size 1.27 1.27)
				)
				(justify mirror)
			)
		)
		(duplicate_pad_numbers_are_jumpers no)
		(fp_line
			(start -0.299974 0.150114)
			(end 0.299974 0.150114)
			(stroke
				(width 0.1)
				(type default)
			)
			(layer "B.Fab")
		)
		(fp_line
			(start 0.299974 0.150114)
			(end 0.299974 -0.150114)
			(stroke
				(width 0.1)
				(type default)
			)
			(layer "B.Fab")
		)
		(fp_line
			(start -0.299974 -0.150114)
			(end -0.299974 0.150114)
			(stroke
				(width 0.1)
				(type default)
			)
			(layer "B.Fab")
		)
		(fp_line
			(start 0.299974 -0.150114)
			(end -0.299974 -0.150114)
			(stroke
				(width 0.1)
				(type default)
			)
			(layer "B.Fab")
		)
		(pad "1" smd rect
			(at 0.2667 0 90)
			(size 0.3048 0.381)
			(layers "B.Cu" "B.Mask" "B.Paste")
			(net "P1V25_SERDES_VDDPLL_PEX0")
		)
		(pad "2" smd rect
			(at -0.2667 0 90)
			(size 0.3048 0.381)
			(layers "B.Cu" "B.Mask" "B.Paste")
			(net "GND")
		)
	)
	(footprint ""
		(layer "B.Cu")
		(at 162.4457 -297.32478)
		(property "Reference" "C3202"
			(at 0 0 0)
			(layer "B.SilkS")
			(hide yes)
			(effects
				(font
					(size 1.27 1.27)
				)
				(justify mirror)
			)
		)
		(property "Value" ""
			(at 0 0 0)
			(layer "B.Fab")
			(effects
				(font
					(size 1.27 1.27)
				)
				(justify mirror)
			)
		)
		(duplicate_pad_numbers_are_jumpers no)
		(fp_line
			(start -0.299974 -0.150114)
			(end -0.299974 0.150114)
			(stroke
				(width 0.1)
				(type default)
			)
			(layer "B.Fab")
		)
		(fp_line
			(start -0.299974 0.150114)
			(end 0.299974 0.150114)
			(stroke
				(width 0.1)
				(type default)
			)
			(layer "B.Fab")
		)
		(fp_line
			(start 0.299974 -0.150114)
			(end -0.299974 -0.150114)
			(stroke
				(width 0.1)
				(type default)
			)
			(layer "B.Fab")
		)
		(fp_line
			(start 0.299974 0.150114)
			(end 0.299974 -0.150114)
			(stroke
				(width 0.1)
				(type default)
			)
			(layer "B.Fab")
		)
		(pad "1" smd rect
			(at 0.2667 0 180)
			(size 0.3048 0.381)
			(layers "B.Cu" "B.Mask" "B.Paste")
			(net "PCEPLL2_VDDA18_PEX1")
		)
		(pad "2" smd rect
			(at -0.2667 0 180)
			(size 0.3048 0.381)
			(layers "B.Cu" "B.Mask" "B.Paste")
			(net "GND")
		)
	)
)
